# T6G (Grand Teton) — schematic netlist excerpt (pin names and nets, part order shuffled) for the footprints in the layout excerpt that follows; sources: Cadence DE-HDL packaged netlist, KiCad conversion of 04192023_DAF0TMB3IC0_F0TG_MB_C_brd_V02_OCP.brd

R674  Q_RES  22 1% CHIP  pkg 0201LF  page 320 : A = SMB_RT_CPU1_P0_ROM_MUX_1D_SCL ; B = SMB_RT_CPU1_P0_ROM_MUX_1D_R_SCL

(kicad_pcb
	(version 20260206)
	(generator "pcbnew")
	(generator_version "10.0")
	(general
		(thickness 1.6)
		(legacy_teardrops no)
	)
	(paper "A4")
	(title_block
		(title "04192023_DAF0TMB3IC0_F0TG_MB_C_brd_V02_OCP.brd")
		(comment 1 "Grand Teton / footprints 3547-3547 of 8354")
	)
	(layers
		(0 "F.Cu" signal "TOP")
		(4 "In1.Cu" signal "GND")
		(6 "In2.Cu" signal "IN1")
		(8 "In3.Cu" signal "GND1")
		(10 "In4.Cu" signal "IN2")
		(12 "In5.Cu" signal "GND2")
		(14 "In6.Cu" signal "IN3")
		(16 "In7.Cu" signal "GND3")
		(18 "In8.Cu" signal "VCC")
		(20 "In9.Cu" signal "VCC1")
		(22 "In10.Cu" signal "GND4")
		(24 "In11.Cu" signal "IN4")
		(26 "In12.Cu" signal "GND5")
		(28 "In13.Cu" signal "IN5")
		(30 "In14.Cu" signal "GND6")
		(32 "In15.Cu" signal "IN6")
		(34 "In16.Cu" signal "GND7")
		(2 "B.Cu" signal "BOTTOM")
		(9 "F.Adhes" user "F.Adhesive")
		(11 "B.Adhes" user "B.Adhesive")
		(13 "F.Paste" user "Package Geometry/Pastemask Top")
		(15 "B.Paste" user "Package Geometry/Pastemask Bottom")
		(5 "F.SilkS" user "Ref Des/Silkscreen Top")
		(7 "B.SilkS" user "Ref Des/Silkscreen Bottom")
		(1 "F.Mask" user "Board Geometry/Soldermask Top")
		(3 "B.Mask" user "Board Geometry/Soldermask Bottom")
		(17 "Dwgs.User" user "User.Drawings")
		(19 "Cmts.User" user "User.Comments")
		(21 "Eco1.User" user "User.Eco1")
		(23 "Eco2.User" user "User.Eco2")
		(25 "Edge.Cuts" user "Board Geometry/Outline")
		(27 "Margin" user)
		(31 "F.CrtYd" user "Package Geometry/Place Bound Top")
		(29 "B.CrtYd" user "Package Geometry/Place Bound Bottom")
		(35 "F.Fab" user "Ref Des/Assembly Top")
		(33 "B.Fab" user "Ref Des/Assembly Bottom")
	)
	(footprint ""
		(layer "F.Cu")
		(at 42.3672 -378.71654)
		(property "Reference" "R674"
			(at 0 0 0)
			(layer "F.SilkS")
			(hide yes)
			(effects
				(font
					(size 1.27 1.27)
				)
			)
		)
		(property "Value" ""
			(at 0 0 0)
			(layer "F.Fab")
			(effects
				(font
					(size 1.27 1.27)
				)
			)
		)
		(duplicate_pad_numbers_are_jumpers no)
		(fp_line
			(start -0.32512 -0.175006)
			(end 0.32512 -0.175006)
			(stroke
				(width 0.1)
				(type default)
			)
			(layer "F.Fab")
		)
		(fp_line
			(start -0.32512 0.175006)
			(end -0.32512 -0.175006)
			(stroke
				(width 0.1)
				(type default)
			)
			(layer "F.Fab")
		)
		(fp_line
			(start 0.32512 -0.175006)
			(end 0.32512 0.175006)
			(stroke
				(width 0.1)
				(type default)
			)
			(layer "F.Fab")
		)
		(fp_line
			(start 0.32512 0.175006)
			(end -0.32512 0.175006)
			(stroke
				(width 0.1)
				(type default)
			)
			(layer "F.Fab")
		)
		(pad "1" smd rect
			(at -0.2667 0)
			(size 0.3048 0.381)
			(layers "F.Cu" "F.Mask" "F.Paste")
			(net "SMB_RT_CPU1_P0_ROM_MUX_1D_SCL")
		)
		(pad "2" smd rect
			(at 0.2667 0 180)
			(size 0.3048 0.381)
			(layers "F.Cu" "F.Mask" "F.Paste")
			(net "SMB_RT_CPU1_P0_ROM_MUX_1D_R_SCL")
		)
	)
)
